# S9S_MB_2U (Grand Teton) — schematic netlist excerpt (pin names and nets, part order shuffled) for the footprints in the layout excerpt that follows; sources: Cadence DE-HDL packaged netlist, KiCad conversion of 03242023_DA0F0TMBIJ0_F0T_Motherboard_J_brd_V01_OCP.brd

ME17  ME_DUMMY_SYMBOL  QUANTA_LOGO_7X26 EMPTY  pkg QUANTA_LOGO_7X26  page 312
C2177  Q_CAP  0.1UF 25V 10% X7R  pkg 0402  page 250 : A = P12V_OCP_V3_2_ISENSE_TIC ; B = GND
R3536  Q_RES  2.2K 5% CHIP  pkg 0402LF  page 231 : A = P3V3_AUX ; B = SMB_SENSOR_E1S_3V3AUX_SDA

(kicad_pcb
	(version 20260206)
	(generator "pcbnew")
	(generator_version "10.0")
	(general
		(thickness 1.6)
		(legacy_teardrops no)
	)
	(paper "A4")
	(title_block
		(title "03242023_DA0F0TMBIJ0_F0T_Motherboard_J_brd_V01_OCP.brd")
		(comment 1 "Grand Teton / footprints 1637-1639 of 6105")
	)
	(layers
		(0 "F.Cu" signal "TOP")
		(4 "In1.Cu" signal "GND")
		(6 "In2.Cu" signal "IN1")
		(8 "In3.Cu" signal "GND1")
		(10 "In4.Cu" signal "IN2")
		(12 "In5.Cu" signal "GND2")
		(14 "In6.Cu" signal "IN3")
		(16 "In7.Cu" signal "GND3")
		(18 "In8.Cu" signal "VCC")
		(20 "In9.Cu" signal "VCC1")
		(22 "In10.Cu" signal "GND4")
		(24 "In11.Cu" signal "IN4")
		(26 "In12.Cu" signal "GND5")
		(28 "In13.Cu" signal "IN5")
		(30 "In14.Cu" signal "GND6")
		(32 "In15.Cu" signal "IN6")
		(34 "In16.Cu" signal "GND7")
		(2 "B.Cu" signal "BOTTOM")
		(9 "F.Adhes" user "F.Adhesive")
		(11 "B.Adhes" user "B.Adhesive")
		(13 "F.Paste" user "Package Geometry/Pastemask Top")
		(15 "B.Paste" user "Package Geometry/Pastemask Bottom")
		(5 "F.SilkS" user "Ref Des/Silkscreen Top")
		(7 "B.SilkS" user "Ref Des/Silkscreen Bottom")
		(1 "F.Mask" user "Board Geometry/Soldermask Top")
		(3 "B.Mask" user "Board Geometry/Soldermask Bottom")
		(17 "Dwgs.User" user "User.Drawings")
		(19 "Cmts.User" user "User.Comments")
		(21 "Eco1.User" user "User.Eco1")
		(23 "Eco2.User" user "User.Eco2")
		(25 "Edge.Cuts" user "Board Geometry/Outline")
		(27 "Margin" user)
		(31 "F.CrtYd" user "Package Geometry/Place Bound Top")
		(29 "B.CrtYd" user "Package Geometry/Place Bound Bottom")
		(35 "F.Fab" user "Ref Des/Assembly Top")
		(33 "B.Fab" user "Ref Des/Assembly Bottom")
	)
	(footprint ""
		(layer "F.Cu")
		(at 36.930584 -110.587282)
		(property "Reference" "C2177"
			(at 0 0 0)
			(layer "F.SilkS")
			(hide yes)
			(effects
				(font
					(size 1.27 1.27)
				)
			)
		)
		(property "Value" ""
			(at 0 0 0)
			(layer "F.Fab")
			(effects
				(font
					(size 1.27 1.27)
				)
			)
		)
		(duplicate_pad_numbers_are_jumpers no)
		(fp_line
			(start -0.7874 -0.4064)
			(end 0.7874 -0.4064)
			(stroke
				(width 0.1524)
				(type default)
			)
			(layer "F.SilkS")
		)
		(fp_line
			(start -0.7874 0.4064)
			(end -0.7874 -0.4064)
			(stroke
				(width 0.1524)
				(type default)
			)
			(layer "F.SilkS")
		)
		(fp_line
			(start 0.7874 -0.4064)
			(end 0.7874 0.4064)
			(stroke
				(width 0.1524)
				(type default)
			)
			(layer "F.SilkS")
		)
		(fp_line
			(start 0.7874 0.4064)
			(end -0.7874 0.4064)
			(stroke
				(width 0.1524)
				(type default)
			)
			(layer "F.SilkS")
		)
		(fp_line
			(start -0.67945 -0.305054)
			(end -0.12065 -0.305054)
			(stroke
				(width 0.1)
				(type default)
			)
			(layer "F.Fab")
		)
		(fp_line
			(start -0.67945 0.3048)
			(end -0.67945 -0.305054)
			(stroke
				(width 0.1)
				(type default)
			)
			(layer "F.Fab")
		)
		(fp_line
			(start -0.12065 -0.305054)
			(end -0.12065 -0.2794)
			(stroke
				(width 0.1)
				(type default)
			)
			(layer "F.Fab")
		)
		(fp_line
			(start -0.12065 -0.2794)
			(end 0.12065 -0.2794)
			(stroke
				(width 0.1)
				(type default)
			)
			(layer "F.Fab")
		)
		(fp_line
			(start -0.12065 0.2794)
			(end -0.12065 0.3048)
			(stroke
				(width 0.1)
				(type default)
			)
			(layer "F.Fab")
		)
		(fp_line
			(start -0.12065 0.3048)
			(end -0.67945 0.3048)
			(stroke
				(width 0.1)
				(type default)
			)
			(layer "F.Fab")
		)
		(fp_line
			(start 0.120396 0.2794)
			(end -0.12065 0.2794)
			(stroke
				(width 0.1)
				(type default)
			)
			(layer "F.Fab")
		)
		(fp_line
			(start 0.120396 0.3048)
			(end 0.120396 0.2794)
			(stroke
				(width 0.1)
				(type default)
			)
			(layer "F.Fab")
		)
		(fp_line
			(start 0.12065 -0.3048)
			(end 0.67945 -0.3048)
			(stroke
				(width 0.1)
				(type default)
			)
			(layer "F.Fab")
		)
		(fp_line
			(start 0.12065 -0.2794)
			(end 0.12065 -0.3048)
			(stroke
				(width 0.1)
				(type default)
			)
			(layer "F.Fab")
		)
		(fp_line
			(start 0.67945 -0.3048)
			(end 0.67945 0.3048)
			(stroke
				(width 0.1)
				(type default)
			)
			(layer "F.Fab")
		)
		(fp_line
			(start 0.67945 0.3048)
			(end 0.120396 0.3048)
			(stroke
				(width 0.1)
				(type default)
			)
			(layer "F.Fab")
		)
		(pad "1" smd circle
			(at -0.40005 0)
			(size 0 0)
			(layers "F.Cu" "F.Mask" "F.Paste")
			(net "P12V_OCP_V3_2_ISENSE_TIC")
		)
		(pad "2" smd circle
			(at 0.40005 0)
			(size 0 0)
			(layers "F.Cu" "F.Mask" "F.Paste")
			(net "GND")
		)
	)
	(footprint ""
		(layer "F.Cu")
		(at 393.814046 -389.123936)
		(property "Reference" "ME17"
			(at 0 0 0)
			(layer "F.SilkS")
			(hide yes)
			(effects
				(font
					(size 1.27 1.27)
				)
			)
		)
		(property "Value" ""
			(at 0 0 0)
			(layer "F.Fab")
			(effects
				(font
					(size 1.27 1.27)
				)
			)
		)
		(duplicate_pad_numbers_are_jumpers no)
	)
	(footprint ""
		(layer "F.Cu")
		(at 111.332772 -128.075182)
		(property "Reference" "R3536"
			(at 0 0 0)
			(layer "F.SilkS")
			(hide yes)
			(effects
				(font
					(size 1.27 1.27)
				)
			)
		)
		(property "Value" ""
			(at 0 0 0)
			(layer "F.Fab")
			(effects
				(font
					(size 1.27 1.27)
				)
			)
		)
		(duplicate_pad_numbers_are_jumpers no)
		(fp_line
			(start -0.7874 -0.4064)
			(end 0.7874 -0.4064)
			(stroke
				(width 0.1524)
				(type default)
			)
			(layer "F.SilkS")
		)
		(fp_line
			(start -0.7874 0.4064)
			(end -0.7874 -0.4064)
			(stroke
				(width 0.1524)
				(type default)
			)
			(layer "F.SilkS")
		)
		(fp_line
			(start 0.7874 -0.4064)
			(end 0.7874 0.4064)
			(stroke
				(width 0.1524)
				(type default)
			)
			(layer "F.SilkS")
		)
		(fp_line
			(start 0.7874 0.4064)
			(end -0.7874 0.4064)
			(stroke
				(width 0.1524)
				(type default)
			)
			(layer "F.SilkS")
		)
		(fp_line
			(start -0.67945 -0.305054)
			(end -0.12065 -0.305054)
			(stroke
				(width 0.1)
				(type default)
			)
			(layer "F.Fab")
		)
		(fp_line
			(start -0.67945 0.3048)
			(end -0.67945 -0.305054)
			(stroke
				(width 0.1)
				(type default)
			)
			(layer "F.Fab")
		)
		(fp_line
			(start -0.12065 -0.305054)
			(end -0.12065 -0.2794)
			(stroke
				(width 0.1)
				(type default)
			)
			(layer "F.Fab")
		)
		(fp_line
			(start -0.12065 -0.2794)
			(end 0.12065 -0.2794)
			(stroke
				(width 0.1)
				(type default)
			)
			(layer "F.Fab")
		)
		(fp_line
			(start -0.12065 0.2794)
			(end -0.12065 0.3048)
			(stroke
				(width 0.1)
				(type default)
			)
			(layer "F.Fab")
		)
		(fp_line
			(start -0.12065 0.3048)
			(end -0.67945 0.3048)
			(stroke
				(width 0.1)
				(type default)
			)
			(layer "F.Fab")
		)
		(fp_line
			(start 0.120396 0.2794)
			(end -0.12065 0.2794)
			(stroke
				(width 0.1)
				(type default)
			)
			(layer "F.Fab")
		)
		(fp_line
			(start 0.120396 0.3048)
			(end 0.120396 0.2794)
			(stroke
				(width 0.1)
				(type default)
			)
			(layer "F.Fab")
		)
		(fp_line
			(start 0.12065 -0.3048)
			(end 0.67945 -0.3048)
			(stroke
				(width 0.1)
				(type default)
			)
			(layer "F.Fab")
		)
		(fp_line
			(start 0.12065 -0.2794)
			(end 0.12065 -0.3048)
			(stroke
				(width 0.1)
				(type default)
			)
			(layer "F.Fab")
		)
		(fp_line
			(start 0.67945 -0.3048)
			(end 0.67945 0.3048)
			(stroke
				(width 0.1)
				(type default)
			)
			(layer "F.Fab")
		)
		(fp_line
			(start 0.67945 0.3048)
			(end 0.120396 0.3048)
			(stroke
				(width 0.1)
				(type default)
			)
			(layer "F.Fab")
		)
		(pad "1" smd circle
			(at -0.40005 0)
			(size 0 0)
			(layers "F.Cu" "F.Mask" "F.Paste")
			(net "P3V3_AUX")
		)
		(pad "2" smd circle
			(at 0.40005 0)
			(size 0 0)
			(layers "F.Cu" "F.Mask" "F.Paste")
			(net "SMB_SENSOR_E1S_3V3AUX_SDA")
		)
	)
)
